# T6G (Grand Teton) — schematic netlist excerpt (pin names and nets, part order shuffled) for the footprints in the layout excerpt that follows; sources: Cadence DE-HDL packaged netlist, KiCad conversion of 04192023_DAF0TMB3IC0_F0TG_MB_C_brd_V02_OCP.brd

U252  74LVC2G17GW  IC  pkg SOT363  page 128
  A0  = RST_PERST_CPU1_SWB_R_N
  GND  = GND
  A1  = RST_PERST_CPU1_SWB_1_R_N
  B1  = RST_PERST_2_SWB_BUF_R_N
  VCC  = P3V3_AUX
  B0  = RST_PERST_0_SWB_BUF_R_N

C5023  Q_CAP  1000PF 50V 5% X7R  pkg 0402  page 28 : A = RST_CPU0_RSMRST_N ; B = GND

(kicad_pcb
	(version 20260206)
	(generator "pcbnew")
	(generator_version "10.0")
	(general
		(thickness 1.6)
		(legacy_teardrops no)
	)
	(paper "A4")
	(title_block
		(title "04192023_DAF0TMB3IC0_F0TG_MB_C_brd_V02_OCP.brd")
		(comment 1 "Grand Teton / footprints 3535-3536 of 8354")
	)
	(layers
		(0 "F.Cu" signal "TOP")
		(4 "In1.Cu" signal "GND")
		(6 "In2.Cu" signal "IN1")
		(8 "In3.Cu" signal "GND1")
		(10 "In4.Cu" signal "IN2")
		(12 "In5.Cu" signal "GND2")
		(14 "In6.Cu" signal "IN3")
		(16 "In7.Cu" signal "GND3")
		(18 "In8.Cu" signal "VCC")
		(20 "In9.Cu" signal "VCC1")
		(22 "In10.Cu" signal "GND4")
		(24 "In11.Cu" signal "IN4")
		(26 "In12.Cu" signal "GND5")
		(28 "In13.Cu" signal "IN5")
		(30 "In14.Cu" signal "GND6")
		(32 "In15.Cu" signal "IN6")
		(34 "In16.Cu" signal "GND7")
		(2 "B.Cu" signal "BOTTOM")
		(9 "F.Adhes" user "F.Adhesive")
		(11 "B.Adhes" user "B.Adhesive")
		(13 "F.Paste" user "Package Geometry/Pastemask Top")
		(15 "B.Paste" user "Package Geometry/Pastemask Bottom")
		(5 "F.SilkS" user "Ref Des/Silkscreen Top")
		(7 "B.SilkS" user "Ref Des/Silkscreen Bottom")
		(1 "F.Mask" user "Board Geometry/Soldermask Top")
		(3 "B.Mask" user "Board Geometry/Soldermask Bottom")
		(17 "Dwgs.User" user "User.Drawings")
		(19 "Cmts.User" user "User.Comments")
		(21 "Eco1.User" user "User.Eco1")
		(23 "Eco2.User" user "User.Eco2")
		(25 "Edge.Cuts" user "Board Geometry/Outline")
		(27 "Margin" user)
		(31 "F.CrtYd" user "Package Geometry/Place Bound Top")
		(29 "B.CrtYd" user "Package Geometry/Place Bound Bottom")
		(35 "F.Fab" user "Ref Des/Assembly Top")
		(33 "B.Fab" user "Ref Des/Assembly Bottom")
	)
	(footprint ""
		(layer "F.Cu")
		(at 393.353798 -320.627756 180)
		(property "Reference" "C5023"
			(at 0 0 180)
			(layer "F.SilkS")
			(hide yes)
			(effects
				(font
					(size 1.27 1.27)
				)
			)
		)
		(property "Value" ""
			(at 0 0 180)
			(layer "F.Fab")
			(effects
				(font
					(size 1.27 1.27)
				)
			)
		)
		(duplicate_pad_numbers_are_jumpers no)
		(fp_line
			(start 0.7874 0.4064)
			(end -0.7874 0.4064)
			(stroke
				(width 0.1524)
				(type default)
			)
			(layer "F.SilkS")
		)
		(fp_line
			(start 0.7874 -0.4064)
			(end 0.7874 0.4064)
			(stroke
				(width 0.1524)
				(type default)
			)
			(layer "F.SilkS")
		)
		(fp_line
			(start -0.7874 0.4064)
			(end -0.7874 -0.4064)
			(stroke
				(width 0.1524)
				(type default)
			)
			(layer "F.SilkS")
		)
		(fp_line
			(start -0.7874 -0.4064)
			(end 0.7874 -0.4064)
			(stroke
				(width 0.1524)
				(type default)
			)
			(layer "F.SilkS")
		)
		(fp_line
			(start 0.67945 0.3048)
			(end 0.120396 0.3048)
			(stroke
				(width 0.1)
				(type default)
			)
			(layer "F.Fab")
		)
		(fp_line
			(start 0.67945 -0.3048)
			(end 0.67945 0.3048)
			(stroke
				(width 0.1)
				(type default)
			)
			(layer "F.Fab")
		)
		(fp_line
			(start 0.12065 -0.2794)
			(end 0.12065 -0.3048)
			(stroke
				(width 0.1)
				(type default)
			)
			(layer "F.Fab")
		)
		(fp_line
			(start 0.12065 -0.3048)
			(end 0.67945 -0.3048)
			(stroke
				(width 0.1)
				(type default)
			)
			(layer "F.Fab")
		)
		(fp_line
			(start 0.120396 0.3048)
			(end 0.120396 0.2794)
			(stroke
				(width 0.1)
				(type default)
			)
			(layer "F.Fab")
		)
		(fp_line
			(start 0.120396 0.2794)
			(end -0.12065 0.2794)
			(stroke
				(width 0.1)
				(type default)
			)
			(layer "F.Fab")
		)
		(fp_line
			(start -0.12065 0.3048)
			(end -0.67945 0.3048)
			(stroke
				(width 0.1)
				(type default)
			)
			(layer "F.Fab")
		)
		(fp_line
			(start -0.12065 0.2794)
			(end -0.12065 0.3048)
			(stroke
				(width 0.1)
				(type default)
			)
			(layer "F.Fab")
		)
		(fp_line
			(start -0.12065 -0.2794)
			(end 0.12065 -0.2794)
			(stroke
				(width 0.1)
				(type default)
			)
			(layer "F.Fab")
		)
		(fp_line
			(start -0.12065 -0.305054)
			(end -0.12065 -0.2794)
			(stroke
				(width 0.1)
				(type default)
			)
			(layer "F.Fab")
		)
		(fp_line
			(start -0.67945 0.3048)
			(end -0.67945 -0.305054)
			(stroke
				(width 0.1)
				(type default)
			)
			(layer "F.Fab")
		)
		(fp_line
			(start -0.67945 -0.305054)
			(end -0.12065 -0.305054)
			(stroke
				(width 0.1)
				(type default)
			)
			(layer "F.Fab")
		)
		(pad "1" smd circle
			(at -0.40005 0 180)
			(size 0 0)
			(layers "F.Cu" "F.Mask" "F.Paste")
			(net "RST_CPU0_RSMRST_N")
		)
		(pad "2" smd circle
			(at 0.40005 0 180)
			(size 0 0)
			(layers "F.Cu" "F.Mask" "F.Paste")
			(net "GND")
		)
	)
	(footprint ""
		(layer "F.Cu")
		(at 51.435 -435.61)
		(property "Reference" "U252"
			(at -1.821434 -3.3528 0)
			(unlocked yes)
			(layer "F.SilkS")
			(effects
				(font
					(size 0.7874 0.5842)
					(thickness 0.1524)
				)
				(justify left)
			)
		)
		(property "Value" ""
			(at 0 0 0)
			(layer "F.Fab")
			(effects
				(font
					(size 1.27 1.27)
				)
			)
		)
		(duplicate_pad_numbers_are_jumpers no)
		(fp_line
			(start -1.3462 -1.100074)
			(end -0.670052 -1.100074)
			(stroke
				(width 0.1524)
				(type default)
			)
			(layer "F.SilkS")
		)
		(fp_line
			(start -1.3462 1.100074)
			(end -1.3462 -1.100074)
			(stroke
				(width 0.1524)
				(type default)
			)
			(layer "F.SilkS")
		)
		(fp_line
			(start -0.670052 -1.100074)
			(end 0 -0.381)
			(stroke
				(width 0.1524)
				(type default)
			)
			(layer "F.SilkS")
		)
		(fp_line
			(start 0 -0.381)
			(end 0.670052 -1.100074)
			(stroke
				(width 0.1524)
				(type default)
			)
			(layer "F.SilkS")
		)
		(fp_line
			(start 0.670052 -1.100074)
			(end 1.3462 -1.100074)
			(stroke
				(width 0.1524)
				(type default)
			)
			(layer "F.SilkS")
		)
		(fp_line
			(start 1.3462 -1.100074)
			(end 1.3462 1.100074)
			(stroke
				(width 0.1524)
				(type default)
			)
			(layer "F.SilkS")
		)
		(fp_line
			(start 1.3462 1.100074)
			(end -1.3462 1.100074)
			(stroke
				(width 0.1524)
				(type default)
			)
			(layer "F.SilkS")
		)
		(fp_poly
			(pts
				(xy -2.953512 -1.926844) (xy -2.52095 -2.554224) (xy -2.109978 -1.807972)
			)
			(stroke
				(width 0)
				(type default)
			)
			(fill yes)
			(layer "F.SilkS")
		)
		(fp_line
			(start -1.100074 -0.8001)
			(end -0.670052 -0.8001)
			(stroke
				(width 0.1)
				(type default)
			)
			(layer "F.Fab")
		)
		(fp_line
			(start -1.100074 0.8001)
			(end -1.100074 -0.8001)
			(stroke
				(width 0.1)
				(type default)
			)
			(layer "F.Fab")
		)
		(fp_line
			(start -0.670052 -1.100074)
			(end 0.670052 -1.100074)
			(stroke
				(width 0.1)
				(type default)
			)
			(layer "F.Fab")
		)
		(fp_line
			(start -0.670052 -0.8001)
			(end -0.670052 -1.100074)
			(stroke
				(width 0.1)
				(type default)
			)
			(layer "F.Fab")
		)
		(fp_line
			(start -0.670052 0.8001)
			(end -1.100074 0.8001)
			(stroke
				(width 0.1)
				(type default)
			)
			(layer "F.Fab")
		)
		(fp_line
			(start -0.670052 0.8001)
			(end -0.670052 -0.8001)
			(stroke
				(width 0.1)
				(type default)
			)
			(layer "F.Fab")
		)
		(fp_line
			(start -0.670052 1.100074)
			(end -0.670052 0.8001)
			(stroke
				(width 0.1)
				(type default)
			)
			(layer "F.Fab")
		)
		(fp_line
			(start 0.670052 -1.100074)
			(end 0.670052 -0.8001)
			(stroke
				(width 0.1)
				(type default)
			)
			(layer "F.Fab")
		)
		(fp_line
			(start 0.670052 -0.8001)
			(end 0.670052 0.8001)
			(stroke
				(width 0.1)
				(type default)
			)
			(layer "F.Fab")
		)
		(fp_line
			(start 0.670052 -0.8001)
			(end 1.100074 -0.8001)
			(stroke
				(width 0.1)
				(type default)
			)
			(layer "F.Fab")
		)
		(fp_line
			(start 0.670052 0.8001)
			(end 0.670052 1.100074)
			(stroke
				(width 0.1)
				(type default)
			)
			(layer "F.Fab")
		)
		(fp_line
			(start 0.670052 1.100074)
			(end -0.670052 1.100074)
			(stroke
				(width 0.1)
				(type default)
			)
			(layer "F.Fab")
		)
		(fp_line
			(start 1.100074 -0.8001)
			(end 1.100074 0.8001)
			(stroke
				(width 0.1)
				(type default)
			)
			(layer "F.Fab")
		)
		(fp_line
			(start 1.100074 0.8001)
			(end 0.670052 0.8001)
			(stroke
				(width 0.1)
				(type default)
			)
			(layer "F.Fab")
		)
		(fp_poly
			(pts
				(xy -1.524 -0.649986) (xy -2.286 -1.030986) (xy -2.286 -0.268986)
			)
			(stroke
				(width 0)
				(type default)
			)
			(fill yes)
			(layer "F.Fab")
		)
		(pad "1" smd rect
			(at -0.94996 -0.649986 270)
			(size 0.4064 0.508)
			(layers "F.Cu" "F.Mask" "F.Paste")
			(net "RST_PERST_CPU1_SWB_R_N")
		)
		(pad "2" smd rect
			(at -0.94996 0 270)
			(size 0.4064 0.508)
			(layers "F.Cu" "F.Mask" "F.Paste")
			(net "GND")
		)
		(pad "3" smd rect
			(at -0.94996 0.649986 270)
			(size 0.4064 0.508)
			(layers "F.Cu" "F.Mask" "F.Paste")
			(net "RST_PERST_CPU1_SWB_1_R_N")
		)
		(pad "4" smd rect
			(at 0.94996 0.649986 270)
			(size 0.4064 0.508)
			(layers "F.Cu" "F.Mask" "F.Paste")
			(net "RST_PERST_2_SWB_BUF_R_N")
		)
		(pad "5" smd rect
			(at 0.94996 0 270)
			(size 0.4064 0.508)
			(layers "F.Cu" "F.Mask" "F.Paste")
			(net "P3V3_AUX")
		)
		(pad "6" smd rect
			(at 0.94996 -0.649986 270)
			(size 0.4064 0.508)
			(layers "F.Cu" "F.Mask" "F.Paste")
			(net "RST_PERST_0_SWB_BUF_R_N")
		)
	)
)
